(kicad_pcb
	(version 20241229)
	(generator "pcbnew")
	(generator_version "9.0")
	(general
		(thickness 1.6642)
		(legacy_teardrops no)
	)
	(paper "A3")
	(title_block
		(title "PolarFire SoM")
		(date "2025-07-22")
		(rev "1.1.4")
		(company "Antmicro Ltd")
		(comment 1 "www.antmicro.com")
		(comment 9 "footprints 191-194 of 470")
	)
	(layers
		(0 "F.Cu" mixed)
		(4 "In1.Cu" power)
		(6 "In2.Cu" signal)
		(8 "In3.Cu" power)
		(10 "In4.Cu" signal)
		(12 "In5.Cu" power)
		(14 "In6.Cu" power)
		(16 "In7.Cu" signal)
		(18 "In8.Cu" power)
		(20 "In9.Cu" signal)
		(22 "In10.Cu" power)
		(24 "In11.Cu" signal)
		(26 "In12.Cu" signal)
		(2 "B.Cu" mixed)
		(9 "F.Adhes" user "F.Adhesive")
		(11 "B.Adhes" user "B.Adhesive")
		(13 "F.Paste" user)
		(15 "B.Paste" user)
		(5 "F.SilkS" user "F.Silkscreen")
		(7 "B.SilkS" user "B.Silkscreen")
		(1 "F.Mask" user)
		(3 "B.Mask" user)
		(17 "Dwgs.User" user "User.Drawings")
		(19 "Cmts.User" user "User.Comments")
		(21 "Eco1.User" user "User.Eco1")
		(23 "Eco2.User" user "User.Eco2")
		(25 "Edge.Cuts" user)
		(27 "Margin" user)
		(31 "F.CrtYd" user "F.Courtyard")
		(29 "B.CrtYd" user "B.Courtyard")
		(35 "F.Fab" user)
		(33 "B.Fab" user)
	)
	(footprint "antmicro-footprints:C_0402_1005Metric"
		(layer "B.Cu")
		(at 177.625 122.5)
		(descr "Capacitor SMD 0402")
		(tags "capacitor SMD 0402")
		(property "Reference" "C154"
			(at -0.925 -0.58 0)
			(layer "B.SilkS")
			(effects
				(font
					(size 0.7 0.7)
					(thickness 0.15)
				)
				(justify right bottom mirror)
			)
		)
		(property "Value" "C_1u_0402"
			(at -1.022927 -2.155213 0)
			(layer "B.Fab")
			(hide yes)
			(effects
				(font
					(size 0.7 0.7)
					(thickness 0.15)
				)
				(justify right bottom mirror)
			)
		)
		(property "Datasheet" "https://product.tdk.com/en/search/capacitor/ceramic/mlcc/info?part_no=C1005X6S1A105K050BC"
			(at 0 0 0)
			(layer "F.Fab")
			(hide yes)
			(effects
				(font
					(size 1.27 1.27)
					(thickness 0.15)
				)
			)
		)
		(property "Description" "SMD Multilayer Ceramic Capacitor, 1 µF, 10 V, 0402 [1005 Metric], ± 10%, X6S, C"
			(at 0 0 0)
			(layer "F.Fab")
			(hide yes)
			(effects
				(font
					(size 1.27 1.27)
					(thickness 0.15)
				)
			)
		)
		(property "Author" "Antmicro"
			(at 0 0 0)
			(layer "B.Fab")
			(hide yes)
			(effects
				(font
					(size 1 1)
					(thickness 0.15)
				)
				(justify mirror)
			)
		)
		(property "Dielectric" "X5R"
			(at 0 0 0)
			(layer "B.Fab")
			(hide yes)
			(effects
				(font
					(size 1 1)
					(thickness 0.15)
				)
				(justify mirror)
			)
		)
		(property "License" "Apache-2.0"
			(at 0 0 0)
			(layer "B.Fab")
			(hide yes)
			(effects
				(font
					(size 1 1)
					(thickness 0.15)
				)
				(justify mirror)
			)
		)
		(property "MPN" "C1005X6S1A105K050BC"
			(at 0 0 0)
			(layer "B.Fab")
			(hide yes)
			(effects
				(font
					(size 1 1)
					(thickness 0.15)
				)
				(justify mirror)
			)
		)
		(property "Manufacturer" "TDK"
			(at 0 0 0)
			(layer "B.Fab")
			(hide yes)
			(effects
				(font
					(size 1 1)
					(thickness 0.15)
				)
				(justify mirror)
			)
		)
		(property "Public" ""
			(at 0 0 0)
			(layer "B.Fab")
			(hide yes)
			(effects
				(font
					(size 1 1)
					(thickness 0.15)
				)
				(justify mirror)
			)
		)
		(property "Val" "1u"
			(at 0 0 0)
			(layer "B.Fab")
			(hide yes)
			(effects
				(font
					(size 1 1)
					(thickness 0.15)
				)
				(justify mirror)
			)
		)
		(property "Voltage" "16V"
			(at 0 0 0)
			(layer "B.Fab")
			(hide yes)
			(effects
				(font
					(size 1 1)
					(thickness 0.15)
				)
				(justify mirror)
			)
		)
		(sheetname "/LPDDR4/")
		(sheetfile "lpddr.kicad_sch")
		(attr smd)
		(fp_rect
			(start -0.925 0.47)
			(end 0.925 -0.47)
			(stroke
				(width 0.05)
				(type default)
			)
			(fill no)
			(layer "B.CrtYd")
		)
		(fp_line
			(start -0.494 -0.248)
			(end -0.494 0.25)
			(stroke
				(width 0.15)
				(type solid)
			)
			(layer "B.Fab")
		)
		(fp_line
			(start -0.494 0.25)
			(end 0.504 0.25)
			(stroke
				(width 0.15)
				(type solid)
			)
			(layer "B.Fab")
		)
		(fp_line
			(start 0.504 -0.248)
			(end -0.494 -0.248)
			(stroke
				(width 0.15)
				(type solid)
			)
			(layer "B.Fab")
		)
		(fp_line
			(start 0.504 0.25)
			(end 0.504 -0.248)
			(stroke
				(width 0.15)
				(type solid)
			)
			(layer "B.Fab")
		)
		(fp_text user "License: Apache-2.0"
			(at -0.939 -5.799 180)
			(layer "B.Fab")
			(effects
				(font
					(size 0.7 0.7)
					(thickness 0.15)
				)
				(justify left bottom mirror)
			)
		)
		(fp_text user "Author: Antmicro"
			(at -0.939 -3.399 180)
			(layer "B.Fab")
			(effects
				(font
					(size 0.7 0.7)
					(thickness 0.15)
				)
				(justify left bottom mirror)
			)
		)
		(fp_text user "${REFERENCE}"
			(at -0.939 -4.599 180)
			(layer "B.Fab")
			(effects
				(font
					(size 0.7 0.7)
					(thickness 0.15)
				)
				(justify left bottom mirror)
			)
		)
		(pad "1" smd roundrect
			(at -0.48 0)
			(size 0.59 0.64)
			(layers "B.Cu" "B.Mask" "B.Paste")
			(roundrect_rratio 0.25)
			(net 417 "GND")
			(pintype "passive")
		)
		(pad "2" smd roundrect
			(at 0.48 0)
			(size 0.59 0.64)
			(layers "B.Cu" "B.Mask" "B.Paste")
			(roundrect_rratio 0.25)
			(net 2 "+1V1")
			(pintype "passive")
		)
	)
	(footprint "antmicro-footprints:C_0402_1005Metric"
		(layer "B.Cu")
		(at 179.1 142.8875)
		(descr "Capacitor SMD 0402")
		(tags "capacitor SMD 0402")
		(property "Reference" "C87"
			(at -1.275 -0.4875 0)
			(layer "B.SilkS")
			(effects
				(font
					(size 0.7 0.7)
					(thickness 0.15)
				)
				(justify right bottom mirror)
			)
		)
		(property "Value" "C_22u_0402"
			(at -1.022927 -2.155213 0)
			(layer "B.Fab")
			(hide yes)
			(effects
				(font
					(size 0.7 0.7)
					(thickness 0.15)
				)
				(justify right bottom mirror)
			)
		)
		(property "Datasheet" "https://www.murata.com/products/productdetail?partno=GRM158R60J226ME01%23"
			(at 0 0 0)
			(layer "F.Fab")
			(hide yes)
			(effects
				(font
					(size 1.27 1.27)
					(thickness 0.15)
				)
			)
		)
		(property "Description" "SMD Multilayer Ceramic Capacitor, 22 uF, 4 V, 0402 [1005 Metric], X6S"
			(at 0 0 0)
			(layer "F.Fab")
			(hide yes)
			(effects
				(font
					(size 1.27 1.27)
					(thickness 0.15)
				)
			)
		)
		(property "Author" "Antmicro"
			(at 0 0 0)
			(layer "B.Fab")
			(hide yes)
			(effects
				(font
					(size 1 1)
					(thickness 0.15)
				)
				(justify mirror)
			)
		)
		(property "Dielectric" ""
			(at 0 0 0)
			(layer "B.Fab")
			(hide yes)
			(effects
				(font
					(size 1 1)
					(thickness 0.15)
				)
				(justify mirror)
			)
		)
		(property "License" "Apache-2.0"
			(at 0 0 0)
			(layer "B.Fab")
			(hide yes)
			(effects
				(font
					(size 1 1)
					(thickness 0.15)
				)
				(justify mirror)
			)
		)
		(property "MPN" "GRM158R60J226ME01D"
			(at 0 0 0)
			(layer "B.Fab")
			(hide yes)
			(effects
				(font
					(size 1 1)
					(thickness 0.15)
				)
				(justify mirror)
			)
		)
		(property "Manufacturer" "Murata"
			(at 0 0 0)
			(layer "B.Fab")
			(hide yes)
			(effects
				(font
					(size 1 1)
					(thickness 0.15)
				)
				(justify mirror)
			)
		)
		(property "Public" ""
			(at 0 0 0)
			(layer "B.Fab")
			(hide yes)
			(effects
				(font
					(size 1 1)
					(thickness 0.15)
				)
				(justify mirror)
			)
		)
		(property "Val" "22u"
			(at 0 0 0)
			(layer "B.Fab")
			(hide yes)
			(effects
				(font
					(size 1 1)
					(thickness 0.15)
				)
				(justify mirror)
			)
		)
		(property "Voltage" ""
			(at 0 0 0)
			(layer "B.Fab")
			(hide yes)
			(effects
				(font
					(size 1 1)
					(thickness 0.15)
				)
				(justify mirror)
			)
		)
		(sheetname "/Supply/")
		(sheetfile "supply.kicad_sch")
		(attr smd)
		(fp_rect
			(start -0.925 0.47)
			(end 0.925 -0.47)
			(stroke
				(width 0.05)
				(type default)
			)
			(fill no)
			(layer "B.CrtYd")
		)
		(fp_line
			(start -0.494 -0.248)
			(end -0.494 0.25)
			(stroke
				(width 0.15)
				(type solid)
			)
			(layer "B.Fab")
		)
		(fp_line
			(start -0.494 0.25)
			(end 0.504 0.25)
			(stroke
				(width 0.15)
				(type solid)
			)
			(layer "B.Fab")
		)
		(fp_line
			(start 0.504 -0.248)
			(end -0.494 -0.248)
			(stroke
				(width 0.15)
				(type solid)
			)
			(layer "B.Fab")
		)
		(fp_line
			(start 0.504 0.25)
			(end 0.504 -0.248)
			(stroke
				(width 0.15)
				(type solid)
			)
			(layer "B.Fab")
		)
		(fp_text user "Author: Antmicro"
			(at -0.939 -3.399 180)
			(layer "B.Fab")
			(effects
				(font
					(size 0.7 0.7)
					(thickness 0.15)
				)
				(justify left bottom mirror)
			)
		)
		(fp_text user "${REFERENCE}"
			(at -0.939 -4.599 180)
			(layer "B.Fab")
			(effects
				(font
					(size 0.7 0.7)
					(thickness 0.15)
				)
				(justify left bottom mirror)
			)
		)
		(fp_text user "License: Apache-2.0"
			(at -0.939 -5.799 180)
			(layer "B.Fab")
			(effects
				(font
					(size 0.7 0.7)
					(thickness 0.15)
				)
				(justify left bottom mirror)
			)
		)
		(pad "1" smd roundrect
			(at -0.48 0)
			(size 0.59 0.64)
			(layers "B.Cu" "B.Mask" "B.Paste")
			(roundrect_rratio 0.25)
			(net 417 "GND")
			(pintype "passive")
		)
		(pad "2" smd roundrect
			(at 0.48 0)
			(size 0.59 0.64)
			(layers "B.Cu" "B.Mask" "B.Paste")
			(roundrect_rratio 0.25)
			(net 90 "+5V")
			(pintype "passive")
		)
	)
	(footprint "antmicro-footprints:C_0402_1005Metric"
		(layer "B.Cu")
		(at 181.1 142.8875 180)
		(descr "Capacitor SMD 0402")
		(tags "capacitor SMD 0402")
		(property "Reference" "C90"
			(at -1.175 0.4875 180)
			(layer "B.SilkS")
			(effects
				(font
					(size 0.7 0.7)
					(thickness 0.15)
				)
				(justify left bottom mirror)
			)
		)
		(property "Value" "C_22u_0402"
			(at -1.022927 -2.155213 0)
			(layer "B.Fab")
			(hide yes)
			(effects
				(font
					(size 0.7 0.7)
					(thickness 0.15)
				)
				(justify left bottom mirror)
			)
		)
		(property "Datasheet" "https://www.murata.com/products/productdetail?partno=GRM158R60J226ME01%23"
			(at 0 0 180)
			(layer "F.Fab")
			(hide yes)
			(effects
				(font
					(size 1.27 1.27)
					(thickness 0.15)
				)
			)
		)
		(property "Description" "SMD Multilayer Ceramic Capacitor, 22 uF, 4 V, 0402 [1005 Metric], X6S"
			(at 0 0 180)
			(layer "F.Fab")
			(hide yes)
			(effects
				(font
					(size 1.27 1.27)
					(thickness 0.15)
				)
			)
		)
		(property "Author" "Antmicro"
			(at 362.2 285.775 0)
			(layer "B.Fab")
			(hide yes)
			(effects
				(font
					(size 1 1)
					(thickness 0.15)
				)
				(justify mirror)
			)
		)
		(property "Dielectric" ""
			(at 362.2 285.775 0)
			(layer "B.Fab")
			(hide yes)
			(effects
				(font
					(size 1 1)
					(thickness 0.15)
				)
				(justify mirror)
			)
		)
		(property "License" "Apache-2.0"
			(at 362.2 285.775 0)
			(layer "B.Fab")
			(hide yes)
			(effects
				(font
					(size 1 1)
					(thickness 0.15)
				)
				(justify mirror)
			)
		)
		(property "MPN" "GRM158R60J226ME01D"
			(at 362.2 285.775 0)
			(layer "B.Fab")
			(hide yes)
			(effects
				(font
					(size 1 1)
					(thickness 0.15)
				)
				(justify mirror)
			)
		)
		(property "Manufacturer" "Murata"
			(at 362.2 285.775 0)
			(layer "B.Fab")
			(hide yes)
			(effects
				(font
					(size 1 1)
					(thickness 0.15)
				)
				(justify mirror)
			)
		)
		(property "Public" ""
			(at 362.2 285.775 0)
			(layer "B.Fab")
			(hide yes)
			(effects
				(font
					(size 1 1)
					(thickness 0.15)
				)
				(justify mirror)
			)
		)
		(property "Val" "22u"
			(at 362.2 285.775 0)
			(layer "B.Fab")
			(hide yes)
			(effects
				(font
					(size 1 1)
					(thickness 0.15)
				)
				(justify mirror)
			)
		)
		(property "Voltage" ""
			(at 362.2 285.775 0)
			(layer "B.Fab")
			(hide yes)
			(effects
				(font
					(size 1 1)
					(thickness 0.15)
				)
				(justify mirror)
			)
		)
		(sheetname "/Supply/")
		(sheetfile "supply.kicad_sch")
		(attr smd)
		(fp_rect
			(start -0.925 0.47)
			(end 0.925 -0.47)
			(stroke
				(width 0.05)
				(type default)
			)
			(fill no)
			(layer "B.CrtYd")
		)
		(fp_line
			(start 0.504 0.25)
			(end 0.504 -0.248)
			(stroke
				(width 0.15)
				(type solid)
			)
			(layer "B.Fab")
		)
		(fp_line
			(start 0.504 -0.248)
			(end -0.494 -0.248)
			(stroke
				(width 0.15)
				(type solid)
			)
			(layer "B.Fab")
		)
		(fp_line
			(start -0.494 0.25)
			(end 0.504 0.25)
			(stroke
				(width 0.15)
				(type solid)
			)
			(layer "B.Fab")
		)
		(fp_line
			(start -0.494 -0.248)
			(end -0.494 0.25)
			(stroke
				(width 0.15)
				(type solid)
			)
			(layer "B.Fab")
		)
		(fp_text user "${REFERENCE}"
			(at -0.939 -4.599 0)
			(layer "B.Fab")
			(effects
				(font
					(size 0.7 0.7)
					(thickness 0.15)
				)
				(justify left bottom mirror)
			)
		)
		(fp_text user "License: Apache-2.0"
			(at -0.939 -5.799 0)
			(layer "B.Fab")
			(effects
				(font
					(size 0.7 0.7)
					(thickness 0.15)
				)
				(justify left bottom mirror)
			)
		)
		(fp_text user "Author: Antmicro"
			(at -0.939 -3.399 0)
			(layer "B.Fab")
			(effects
				(font
					(size 0.7 0.7)
					(thickness 0.15)
				)
				(justify left bottom mirror)
			)
		)
		(pad "1" smd roundrect
			(at -0.48 0 180)
			(size 0.59 0.64)
			(layers "B.Cu" "B.Mask" "B.Paste")
			(roundrect_rratio 0.25)
			(net 417 "GND")
			(pintype "passive")
		)
		(pad "2" smd roundrect
			(at 0.48 0 180)
			(size 0.59 0.64)
			(layers "B.Cu" "B.Mask" "B.Paste")
			(roundrect_rratio 0.25)
			(net 90 "+5V")
			(pintype "passive")
		)
	)
	(footprint "antmicro-footprints:R_0402_1005Metric"
		(layer "B.Cu")
		(at 183.425 132.175)
		(descr "Resistor SMD 0402")
		(tags "resistor SMD 0402")
		(property "Reference" "R104"
			(at -0.815 -0.505 0)
			(layer "B.SilkS")
			(effects
				(font
					(size 0.7 0.7)
					(thickness 0.15)
				)
				(justify right bottom mirror)
			)
		)
		(property "Value" "R_10k_0402"
			(at -1.011843 -1.772047 0)
			(layer "B.Fab")
			(hide yes)
			(effects
				(font
					(size 0.7 0.7)
					(thickness 0.15)
				)
				(justify right bottom mirror)
			)
		)
		(property "Datasheet" "https://www.bourns.com/docs/product-datasheets/cr.pdf"
			(at 0 0 0)
			(layer "F.Fab")
			(hide yes)
			(effects
				(font
					(size 1.27 1.27)
					(thickness 0.15)
				)
			)
		)
		(property "Description" "SMD Chip Resistor, 10 kohm, ± 1%, 62.5 mW, 0402 [1005 Metric], Thick Film, General Purpose"
			(at 0 0 0)
			(layer "F.Fab")
			(hide yes)
			(effects
				(font
					(size 1.27 1.27)
					(thickness 0.15)
				)
			)
		)
		(property "Author" "Antmicro"
			(at 0 0 0)
			(layer "B.Fab")
			(hide yes)
			(effects
				(font
					(size 1 1)
					(thickness 0.15)
				)
				(justify mirror)
			)
		)
		(property "License" "Apache-2.0"
			(at 0 0 0)
			(layer "B.Fab")
			(hide yes)
			(effects
				(font
					(size 1 1)
					(thickness 0.15)
				)
				(justify mirror)
			)
		)
		(property "MPN" "CR0402-FX-1002GLF"
			(at 0 0 0)
			(layer "B.Fab")
			(hide yes)
			(effects
				(font
					(size 1 1)
					(thickness 0.15)
				)
				(justify mirror)
			)
		)
		(property "Manufacturer" "Bourns"
			(at 0 0 0)
			(layer "B.Fab")
			(hide yes)
			(effects
				(font
					(size 1 1)
					(thickness 0.15)
				)
				(justify mirror)
			)
		)
		(property "Public" ""
			(at 0 0 0)
			(layer "B.Fab")
			(hide yes)
			(effects
				(font
					(size 1 1)
					(thickness 0.15)
				)
				(justify mirror)
			)
		)
		(property "Tolerance" "1%"
			(at 0 0 0)
			(layer "B.Fab")
			(hide yes)
			(effects
				(font
					(size 1 1)
					(thickness 0.15)
				)
				(justify mirror)
			)
		)
		(property "Val" "10k"
			(at 0 0 0)
			(layer "B.Fab")
			(hide yes)
			(effects
				(font
					(size 1 1)
					(thickness 0.15)
				)
				(justify mirror)
			)
		)
		(sheetname "/LPDDR4/")
		(sheetfile "lpddr.kicad_sch")
		(attr smd)
		(fp_rect
			(start -0.925 0.47)
			(end 0.925 -0.47)
			(stroke
				(width 0.05)
				(type default)
			)
			(fill no)
			(layer "B.CrtYd")
		)
		(fp_rect
			(start -0.5 0.25)
			(end 0.5 -0.25)
			(stroke
				(width 0.15)
				(type solid)
			)
			(fill no)
			(layer "B.Fab")
		)
		(fp_text user "License: Apache-2.0"
			(at -0.95 -5.169 180)
			(layer "B.Fab")
			(effects
				(font
					(size 0.7 0.7)
					(thickness 0.15)
				)
				(justify left bottom mirror)
			)
		)
		(fp_text user "${REFERENCE}"
			(at -0.95 -3.168 180)
			(layer "B.Fab")
			(effects
				(font
					(size 0.7 0.7)
					(thickness 0.15)
				)
				(justify left bottom mirror)
			)
		)
		(fp_text user "Author: Antmicro"
			(at -0.95 -4.169 180)
			(layer "B.Fab")
			(effects
				(font
					(size 0.7 0.7)
					(thickness 0.15)
				)
				(justify left bottom mirror)
			)
		)
		(pad "1" smd roundrect
			(at -0.48 0)
			(size 0.59 0.64)
			(layers "B.Cu" "B.Mask" "B.Paste")
			(roundrect_rratio 0.25)
			(net 417 "GND")
			(pintype "passive")
		)
		(pad "2" smd roundrect
			(at 0.48 0)
			(size 0.59 0.64)
			(layers "B.Cu" "B.Mask" "B.Paste")
			(roundrect_rratio 0.25)
			(net 394 "/FPGA MSS/LPDDR4.RESET_n")
			(pintype "passive")
		)
	)
)
